# S9S_MB_2U (Grand Teton) — schematic netlist excerpt (pin names and nets, part order shuffled) for the footprints in the layout excerpt that follows; sources: Cadence DE-HDL packaged netlist, KiCad conversion of 03242023_DA0F0TMBIJ0_F0T_Motherboard_J_brd_V01_OCP.brd

R3192  Q_RES  4.7K 1% EMPTY  pkg 0402LF  page 161 : A = P3V3_AUX ; B = IRQ_LVC3_V3_2_WAKE_BUF_N
R4276  Q_RES  68K 1% CHIP  pkg 0402LF  page 169 : A = FM_USB3_1_EQA ; B = GND

(kicad_pcb
	(version 20260206)
	(generator "pcbnew")
	(generator_version "10.0")
	(general
		(thickness 1.6)
		(legacy_teardrops no)
	)
	(paper "A4")
	(title_block
		(title "03242023_DA0F0TMBIJ0_F0T_Motherboard_J_brd_V01_OCP.brd")
		(comment 1 "Grand Teton / footprints 601-602 of 6105")
	)
	(layers
		(0 "F.Cu" signal "TOP")
		(4 "In1.Cu" signal "GND")
		(6 "In2.Cu" signal "IN1")
		(8 "In3.Cu" signal "GND1")
		(10 "In4.Cu" signal "IN2")
		(12 "In5.Cu" signal "GND2")
		(14 "In6.Cu" signal "IN3")
		(16 "In7.Cu" signal "GND3")
		(18 "In8.Cu" signal "VCC")
		(20 "In9.Cu" signal "VCC1")
		(22 "In10.Cu" signal "GND4")
		(24 "In11.Cu" signal "IN4")
		(26 "In12.Cu" signal "GND5")
		(28 "In13.Cu" signal "IN5")
		(30 "In14.Cu" signal "GND6")
		(32 "In15.Cu" signal "IN6")
		(34 "In16.Cu" signal "GND7")
		(2 "B.Cu" signal "BOTTOM")
		(9 "F.Adhes" user "F.Adhesive")
		(11 "B.Adhes" user "B.Adhesive")
		(13 "F.Paste" user "Package Geometry/Pastemask Top")
		(15 "B.Paste" user "Package Geometry/Pastemask Bottom")
		(5 "F.SilkS" user "Ref Des/Silkscreen Top")
		(7 "B.SilkS" user "Ref Des/Silkscreen Bottom")
		(1 "F.Mask" user "Board Geometry/Soldermask Top")
		(3 "B.Mask" user "Board Geometry/Soldermask Bottom")
		(17 "Dwgs.User" user "User.Drawings")
		(19 "Cmts.User" user "User.Comments")
		(21 "Eco1.User" user "User.Eco1")
		(23 "Eco2.User" user "User.Eco2")
		(25 "Edge.Cuts" user "Board Geometry/Outline")
		(27 "Margin" user)
		(31 "F.CrtYd" user "Package Geometry/Place Bound Top")
		(29 "B.CrtYd" user "Package Geometry/Place Bound Bottom")
		(35 "F.Fab" user "Ref Des/Assembly Top")
		(33 "B.Fab" user "Ref Des/Assembly Bottom")
	)
	(footprint ""
		(layer "F.Cu")
		(at 136.60628 -26.251408)
		(property "Reference" "R4276"
			(at 0 0 0)
			(layer "F.SilkS")
			(hide yes)
			(effects
				(font
					(size 1.27 1.27)
				)
			)
		)
		(property "Value" ""
			(at 0 0 0)
			(layer "F.Fab")
			(effects
				(font
					(size 1.27 1.27)
				)
			)
		)
		(duplicate_pad_numbers_are_jumpers no)
		(fp_line
			(start -0.7874 -0.4064)
			(end 0.7874 -0.4064)
			(stroke
				(width 0.1524)
				(type default)
			)
			(layer "F.SilkS")
		)
		(fp_line
			(start -0.7874 0.4064)
			(end -0.7874 -0.4064)
			(stroke
				(width 0.1524)
				(type default)
			)
			(layer "F.SilkS")
		)
		(fp_line
			(start 0.7874 -0.4064)
			(end 0.7874 0.4064)
			(stroke
				(width 0.1524)
				(type default)
			)
			(layer "F.SilkS")
		)
		(fp_line
			(start 0.7874 0.4064)
			(end -0.7874 0.4064)
			(stroke
				(width 0.1524)
				(type default)
			)
			(layer "F.SilkS")
		)
		(fp_line
			(start -0.67945 -0.305054)
			(end -0.12065 -0.305054)
			(stroke
				(width 0.1)
				(type default)
			)
			(layer "F.Fab")
		)
		(fp_line
			(start -0.67945 0.3048)
			(end -0.67945 -0.305054)
			(stroke
				(width 0.1)
				(type default)
			)
			(layer "F.Fab")
		)
		(fp_line
			(start -0.12065 -0.305054)
			(end -0.12065 -0.2794)
			(stroke
				(width 0.1)
				(type default)
			)
			(layer "F.Fab")
		)
		(fp_line
			(start -0.12065 -0.2794)
			(end 0.12065 -0.2794)
			(stroke
				(width 0.1)
				(type default)
			)
			(layer "F.Fab")
		)
		(fp_line
			(start -0.12065 0.2794)
			(end -0.12065 0.3048)
			(stroke
				(width 0.1)
				(type default)
			)
			(layer "F.Fab")
		)
		(fp_line
			(start -0.12065 0.3048)
			(end -0.67945 0.3048)
			(stroke
				(width 0.1)
				(type default)
			)
			(layer "F.Fab")
		)
		(fp_line
			(start 0.120396 0.2794)
			(end -0.12065 0.2794)
			(stroke
				(width 0.1)
				(type default)
			)
			(layer "F.Fab")
		)
		(fp_line
			(start 0.120396 0.3048)
			(end 0.120396 0.2794)
			(stroke
				(width 0.1)
				(type default)
			)
			(layer "F.Fab")
		)
		(fp_line
			(start 0.12065 -0.3048)
			(end 0.67945 -0.3048)
			(stroke
				(width 0.1)
				(type default)
			)
			(layer "F.Fab")
		)
		(fp_line
			(start 0.12065 -0.2794)
			(end 0.12065 -0.3048)
			(stroke
				(width 0.1)
				(type default)
			)
			(layer "F.Fab")
		)
		(fp_line
			(start 0.67945 -0.3048)
			(end 0.67945 0.3048)
			(stroke
				(width 0.1)
				(type default)
			)
			(layer "F.Fab")
		)
		(fp_line
			(start 0.67945 0.3048)
			(end 0.120396 0.3048)
			(stroke
				(width 0.1)
				(type default)
			)
			(layer "F.Fab")
		)
		(pad "1" smd circle
			(at -0.40005 0)
			(size 0 0)
			(layers "F.Cu" "F.Mask" "F.Paste")
			(net "FM_USB3_1_EQA")
		)
		(pad "2" smd circle
			(at 0.40005 0)
			(size 0 0)
			(layers "F.Cu" "F.Mask" "F.Paste")
			(net "GND")
		)
	)
	(footprint ""
		(layer "F.Cu")
		(at 280.840688 -15.247112 180)
		(property "Reference" "R3192"
			(at 0 0 180)
			(layer "F.SilkS")
			(hide yes)
			(effects
				(font
					(size 1.27 1.27)
				)
			)
		)
		(property "Value" ""
			(at 0 0 180)
			(layer "F.Fab")
			(effects
				(font
					(size 1.27 1.27)
				)
			)
		)
		(duplicate_pad_numbers_are_jumpers no)
		(fp_line
			(start 0.7874 0.4064)
			(end -0.7874 0.4064)
			(stroke
				(width 0.1524)
				(type default)
			)
			(layer "F.SilkS")
		)
		(fp_line
			(start 0.7874 -0.4064)
			(end 0.7874 0.4064)
			(stroke
				(width 0.1524)
				(type default)
			)
			(layer "F.SilkS")
		)
		(fp_line
			(start -0.7874 0.4064)
			(end -0.7874 -0.4064)
			(stroke
				(width 0.1524)
				(type default)
			)
			(layer "F.SilkS")
		)
		(fp_line
			(start -0.7874 -0.4064)
			(end 0.7874 -0.4064)
			(stroke
				(width 0.1524)
				(type default)
			)
			(layer "F.SilkS")
		)
		(fp_line
			(start 0.67945 0.3048)
			(end 0.120396 0.3048)
			(stroke
				(width 0.1)
				(type default)
			)
			(layer "F.Fab")
		)
		(fp_line
			(start 0.67945 -0.3048)
			(end 0.67945 0.3048)
			(stroke
				(width 0.1)
				(type default)
			)
			(layer "F.Fab")
		)
		(fp_line
			(start 0.12065 -0.2794)
			(end 0.12065 -0.3048)
			(stroke
				(width 0.1)
				(type default)
			)
			(layer "F.Fab")
		)
		(fp_line
			(start 0.12065 -0.3048)
			(end 0.67945 -0.3048)
			(stroke
				(width 0.1)
				(type default)
			)
			(layer "F.Fab")
		)
		(fp_line
			(start 0.120396 0.3048)
			(end 0.120396 0.2794)
			(stroke
				(width 0.1)
				(type default)
			)
			(layer "F.Fab")
		)
		(fp_line
			(start 0.120396 0.2794)
			(end -0.12065 0.2794)
			(stroke
				(width 0.1)
				(type default)
			)
			(layer "F.Fab")
		)
		(fp_line
			(start -0.12065 0.3048)
			(end -0.67945 0.3048)
			(stroke
				(width 0.1)
				(type default)
			)
			(layer "F.Fab")
		)
		(fp_line
			(start -0.12065 0.2794)
			(end -0.12065 0.3048)
			(stroke
				(width 0.1)
				(type default)
			)
			(layer "F.Fab")
		)
		(fp_line
			(start -0.12065 -0.2794)
			(end 0.12065 -0.2794)
			(stroke
				(width 0.1)
				(type default)
			)
			(layer "F.Fab")
		)
		(fp_line
			(start -0.12065 -0.305054)
			(end -0.12065 -0.2794)
			(stroke
				(width 0.1)
				(type default)
			)
			(layer "F.Fab")
		)
		(fp_line
			(start -0.67945 0.3048)
			(end -0.67945 -0.305054)
			(stroke
				(width 0.1)
				(type default)
			)
			(layer "F.Fab")
		)
		(fp_line
			(start -0.67945 -0.305054)
			(end -0.12065 -0.305054)
			(stroke
				(width 0.1)
				(type default)
			)
			(layer "F.Fab")
		)
		(pad "1" smd circle
			(at -0.40005 0 180)
			(size 0 0)
			(layers "F.Cu" "F.Mask" "F.Paste")
			(net "P3V3_AUX")
		)
		(pad "2" smd circle
			(at 0.40005 0 180)
			(size 0 0)
			(layers "F.Cu" "F.Mask" "F.Paste")
			(net "IRQ_LVC3_V3_2_WAKE_BUF_N")
		)
	)
)
